# BASEBOARD_FAB2 (Tioga Pass) — schematic netlist excerpt (pin names and nets, part order shuffled) for the footprints in the layout excerpt that follows; sources: Cadence DE-HDL packaged netlist, KiCad conversion of Wiwynn_Tioga_Pass_MB.brd

R25W41  120R2F-GP  1%  pkg RCL_GP  page 151 : \1\ = BMC_M_A3 ; \2\ = P1V2_AUX_BMC
C6M6  CAP_A  0.1UF 16V 10% X7R  pkg 0402V  page 113 : A = JTAG_MCP_CPU1_TDI_R ; B = GND
C6R13  CAP  10UF 16V 10% X6S  pkg 0805  page 202 : A = VR_FET_SW_P12V_STBY_PVCCIN_CPU0 ; B = GND

(kicad_pcb
	(version 20260206)
	(generator "pcbnew")
	(generator_version "10.0")
	(general
		(thickness 1.6)
		(legacy_teardrops no)
	)
	(paper "A4")
	(title_block
		(title "Wiwynn_Tioga_Pass_MB.brd")
		(comment 1 "Tioga Pass / footprints 3480-3482 of 4770")
	)
	(layers
		(0 "F.Cu" signal "TOP")
		(4 "In1.Cu" signal "L2GND")
		(6 "In2.Cu" signal "L3")
		(8 "In3.Cu" signal "L4GND")
		(10 "In4.Cu" signal "L5")
		(12 "In5.Cu" signal "L6GND")
		(14 "In6.Cu" signal "L7VCC")
		(16 "In7.Cu" signal "L8VCC")
		(18 "In8.Cu" signal "L9GND")
		(20 "In9.Cu" signal "L10")
		(22 "In10.Cu" signal "L11GND")
		(24 "In11.Cu" signal "L12")
		(26 "In12.Cu" signal "L13GND")
		(2 "B.Cu" signal "BOTTOM")
		(9 "F.Adhes" user "F.Adhesive")
		(11 "B.Adhes" user "B.Adhesive")
		(13 "F.Paste" user "Package Geometry/Pastemask Top")
		(15 "B.Paste" user "Package Geometry/Pastemask Bottom")
		(5 "F.SilkS" user "Ref Des/Silkscreen Top")
		(7 "B.SilkS" user "Ref Des/Silkscreen Bottom")
		(1 "F.Mask" user "Board Geometry/Soldermask Top")
		(3 "B.Mask" user "Board Geometry/Soldermask Bottom")
		(17 "Dwgs.User" user "User.Drawings")
		(19 "Cmts.User" user "User.Comments")
		(21 "Eco1.User" user "User.Eco1")
		(23 "Eco2.User" user "User.Eco2")
		(25 "Edge.Cuts" user "Board Geometry/Outline")
		(27 "Margin" user)
		(31 "F.CrtYd" user "Package Geometry/Place Bound Top")
		(29 "B.CrtYd" user "Package Geometry/Place Bound Bottom")
		(35 "F.Fab" user "Ref Des/Assembly Top")
		(33 "B.Fab" user "Ref Des/Assembly Bottom")
	)
	(footprint ""
		(layer "B.Cu")
		(at 439.976006 -43.54195 180)
		(property "Reference" "R25W41"
			(at 0 0 0)
			(layer "B.SilkS")
			(hide yes)
			(effects
				(font
					(size 1.27 1.27)
				)
				(justify mirror)
			)
		)
		(property "Value" "*"
			(at -0.064008 -4.108196 180)
			(unlocked yes)
			(layer "B.Fab")
			(hide yes)
			(effects
				(font
					(size 1.27 1.016)
					(thickness 0.1524)
				)
				(justify mirror)
			)
		)
		(property "Device Type" "120R2F-GP_RCL_GP-120R2F-GP,64.A"
			(at -0.064008 -5.632196 180)
			(unlocked yes)
			(layer "B.Fab")
			(hide yes)
			(effects
				(font
					(size 1.27 1.016)
					(thickness 0.1524)
				)
				(justify mirror)
			)
		)
		(duplicate_pad_numbers_are_jumpers no)
		(fp_line
			(start 0.508 -0.9398)
			(end 0.508 0.9398)
			(stroke
				(width 0.1524)
				(type default)
			)
			(layer "B.SilkS")
		)
		(fp_line
			(start -0.508 -0.9398)
			(end 0.508 -0.9398)
			(stroke
				(width 0.1524)
				(type default)
			)
			(layer "B.SilkS")
		)
		(fp_rect
			(start 0.508 0.9398)
			(end -0.508 -0.9398)
			(stroke
				(width 0)
				(type default)
			)
			(fill no)
			(layer "B.CrtYd")
		)
		(fp_rect
			(start 0.508 0.9398)
			(end -0.508 -0.9398)
			(stroke
				(width 0)
				(type default)
			)
			(fill no)
			(layer "B.Fab")
		)
		(pad "1" smd custom
			(at 0 -0.4445)
			(size 0.1397 0.1397)
			(layers "B.Cu" "B.Mask" "B.Paste")
			(net "BMC_M_A3")
			(options
				(clearance outline)
				(anchor circle)
			)
			(primitives
				(gr_poly
					(pts
						(arc
							(start -0.1778 0.2794)
							(mid -0.249642 0.249642)
							(end -0.2794 0.1778)
						)
						(arc
							(start -0.2794 -0.1778)
							(mid -0.249642 -0.249642)
							(end -0.1778 -0.2794)
						)
						(arc
							(start 0.1778 -0.2794)
							(mid 0.249642 -0.249642)
							(end 0.2794 -0.1778)
						)
						(arc
							(start 0.2794 0.1778)
							(mid 0.249642 0.249642)
							(end 0.1778 0.2794)
						)
					)
					(width 0)
					(fill yes)
				)
			)
		)
		(pad "2" smd custom
			(at 0 0.4445)
			(size 0.1397 0.1397)
			(layers "B.Cu" "B.Mask" "B.Paste")
			(net "P1V2_AUX_BMC")
			(options
				(clearance outline)
				(anchor circle)
			)
			(primitives
				(gr_poly
					(pts
						(arc
							(start -0.1778 0.2794)
							(mid -0.249642 0.249642)
							(end -0.2794 0.1778)
						)
						(arc
							(start -0.2794 -0.1778)
							(mid -0.249642 -0.249642)
							(end -0.1778 -0.2794)
						)
						(arc
							(start 0.1778 -0.2794)
							(mid 0.249642 -0.249642)
							(end 0.2794 -0.1778)
						)
						(arc
							(start 0.2794 0.1778)
							(mid 0.249642 0.249642)
							(end 0.1778 0.2794)
						)
					)
					(width 0)
					(fill yes)
				)
			)
		)
	)
	(footprint ""
		(layer "B.Cu")
		(at 168.656 -125.603 -90)
		(property "Reference" "C6M6"
			(at 0.8382 -0.84963 270)
			(unlocked yes)
			(layer "B.SilkS")
			(effects
				(font
					(size 0.7874 0.5842)
					(thickness 0.1524)
				)
				(justify left mirror)
			)
		)
		(property "Value" ""
			(at 0 0 90)
			(layer "B.Fab")
			(effects
				(font
					(size 1.27 1.27)
				)
				(justify mirror)
			)
		)
		(duplicate_pad_numbers_are_jumpers no)
		(fp_poly
			(pts
				(xy -0.3048 -0.1016) (xy -0.3048 0.9906) (xy 0.3048 0.9906) (xy 0.3048 -0.1016)
			)
			(stroke
				(width 0)
				(type default)
			)
			(fill no)
			(layer "B.CrtYd")
		)
		(fp_line
			(start -0.3048 0.9906)
			(end -0.3048 -0.1016)
			(stroke
				(width 0.1)
				(type default)
			)
			(layer "B.Fab")
		)
		(fp_line
			(start 0.3048 0.9906)
			(end -0.3048 0.9906)
			(stroke
				(width 0.1)
				(type default)
			)
			(layer "B.Fab")
		)
		(fp_line
			(start -0.3048 -0.1016)
			(end 0.3048 -0.1016)
			(stroke
				(width 0.1)
				(type default)
			)
			(layer "B.Fab")
		)
		(fp_line
			(start 0.3048 -0.1016)
			(end 0.3048 0.9906)
			(stroke
				(width 0.1)
				(type default)
			)
			(layer "B.Fab")
		)
		(pad "1" smd rect
			(at 0 0 90)
			(size 0.508 0.508)
			(layers "B.Cu" "B.Mask" "B.Paste")
			(net "JTAG_MCP_CPU1_TDI_R")
		)
		(pad "2" smd rect
			(at 0 0.889 90)
			(size 0.508 0.508)
			(layers "B.Cu" "B.Mask" "B.Paste")
			(net "GND")
		)
		(zone
			(layer "B.Cu")
			(hatch none 0.5)
			(connect_pads
				(clearance 0)
			)
			(min_thickness 0.25)
			(keepout
				(tracks not_allowed)
				(vias allowed)
				(pads allowed)
				(copperpour not_allowed)
				(footprints allowed)
			)
			(placement
				(enabled no)
				(sheetname "")
			)
			(fill
				(thermal_gap 0.5)
				(thermal_bridge_width 0.5)
				(island_removal_mode 0)
			)
			(polygon
				(pts
					(xy 168.021 -125.349) (xy 168.021 -125.857) (xy 168.402 -125.857) (xy 168.402 -125.349)
				)
			)
		)
		(zone
			(layer "B.Cu")
			(hatch none 0.5)
			(connect_pads
				(clearance 0)
			)
			(min_thickness 0.25)
			(keepout
				(tracks allowed)
				(vias not_allowed)
				(pads allowed)
				(copperpour not_allowed)
				(footprints allowed)
			)
			(placement
				(enabled no)
				(sheetname "")
			)
			(fill
				(thermal_gap 0.5)
				(thermal_bridge_width 0.5)
				(island_removal_mode 0)
			)
			(polygon
				(pts
					(xy 168.402 -125.349) (xy 168.402 -125.857) (xy 168.021 -125.857) (xy 168.021 -125.349)
				)
			)
		)
	)
	(footprint ""
		(layer "B.Cu")
		(at 197.866 -56.7182 90)
		(property "Reference" "C6R13"
			(at 0 0 90)
			(layer "B.SilkS")
			(hide yes)
			(effects
				(font
					(size 1.27 1.27)
				)
				(justify mirror)
			)
		)
		(property "Value" ""
			(at 0 0 90)
			(layer "B.Fab")
			(effects
				(font
					(size 1.27 1.27)
				)
				(justify mirror)
			)
		)
		(duplicate_pad_numbers_are_jumpers no)
		(fp_rect
			(start -0.7239 -0.2159)
			(end 0.7239 1.9939)
			(stroke
				(width 0)
				(type default)
			)
			(fill no)
			(layer "B.CrtYd")
		)
		(fp_line
			(start 0.7239 -0.2159)
			(end 0.7239 1.9939)
			(stroke
				(width 0.1)
				(type default)
			)
			(layer "B.Fab")
		)
		(fp_line
			(start -0.7239 -0.2159)
			(end 0.7239 -0.2159)
			(stroke
				(width 0.1)
				(type default)
			)
			(layer "B.Fab")
		)
		(fp_line
			(start 0.7239 1.9939)
			(end -0.7239 1.9939)
			(stroke
				(width 0.1)
				(type default)
			)
			(layer "B.Fab")
		)
		(fp_line
			(start -0.7239 1.9939)
			(end -0.7239 -0.2159)
			(stroke
				(width 0.1)
				(type default)
			)
			(layer "B.Fab")
		)
		(pad "1" smd rect
			(at 0 0 270)
			(size 1.27 1.016)
			(layers "B.Cu" "B.Mask" "B.Paste")
			(net "VR_FET_SW_P12V_STBY_PVCCIN_CPU0")
		)
		(pad "2" smd rect
			(at 0 1.778 270)
			(size 1.27 1.016)
			(layers "B.Cu" "B.Mask" "B.Paste")
			(net "GND")
		)
		(zone
			(layer "B.Cu")
			(hatch none 0.5)
			(connect_pads
				(clearance 0)
			)
			(min_thickness 0.25)
			(keepout
				(tracks not_allowed)
				(vias allowed)
				(pads allowed)
				(copperpour not_allowed)
				(footprints allowed)
			)
			(placement
				(enabled no)
				(sheetname "")
			)
			(fill
				(thermal_gap 0.5)
				(thermal_bridge_width 0.5)
				(island_removal_mode 0)
			)
			(polygon
				(pts
					(xy 198.374 -56.0832) (xy 199.136 -56.0832) (xy 199.136 -57.3532) (xy 198.374 -57.3532)
				)
			)
		)
	)
)
